(kicad_pcb
	(version 20260206)
	(generator "pcbnew")
	(generator_version "10.0")
	(general
		(thickness 1.6)
		(legacy_teardrops no)
	)
	(paper "A4")
	(title_block
		(title "Bryce Canyon_R.DPB_16317-1_OCP.brd")
		(comment 1 "Bryce Canyon / footprints 1319-1321 of 2099")
	)
	(layers
		(0 "F.Cu" signal "TOP")
		(4 "In1.Cu" signal "L2GND")
		(6 "In2.Cu" signal "L3")
		(8 "In3.Cu" signal "L4VCC")
		(10 "In4.Cu" signal "L5VCC")
		(12 "In5.Cu" signal "L6")
		(14 "In6.Cu" signal "L7GND")
		(2 "B.Cu" signal "BOTTOM")
		(9 "F.Adhes" user "F.Adhesive")
		(11 "B.Adhes" user "B.Adhesive")
		(13 "F.Paste" user "Package Geometry/Pastemask Top")
		(15 "B.Paste" user "Package Geometry/Pastemask Bottom")
		(5 "F.SilkS" user "Ref Des/Silkscreen Top")
		(7 "B.SilkS" user "Ref Des/Silkscreen Bottom")
		(1 "F.Mask" user "Board Geometry/Soldermask Top")
		(3 "B.Mask" user "Board Geometry/Soldermask Bottom")
		(17 "Dwgs.User" user "User.Drawings")
		(19 "Cmts.User" user "User.Comments")
		(21 "Eco1.User" user "User.Eco1")
		(23 "Eco2.User" user "User.Eco2")
		(25 "Edge.Cuts" user "Board Geometry/Outline")
		(27 "Margin" user)
		(31 "F.CrtYd" user "Package Geometry/Place Bound Top")
		(29 "B.CrtYd" user "Package Geometry/Place Bound Bottom")
		(35 "F.Fab" user "Ref Des/Assembly Top")
		(33 "B.Fab" user "Ref Des/Assembly Bottom")
	)
	(footprint ""
		(layer "F.Cu")
		(at 28.200096 -28.910026 -90)
		(property "Reference" "HDDSAS24"
			(at 0 0 270)
			(layer "F.SilkS")
			(hide yes)
			(effects
				(font
					(size 1.27 1.27)
				)
			)
		)
		(property "Value" "SKT-SAS15P-14P-45-GP"
			(at -20.7645 -8.9789 270)
			(unlocked yes)
			(layer "F.Fab")
			(hide yes)
			(effects
				(font
					(size 1.016 1.016)
					(thickness 0.1524)
				)
			)
		)
		(property "Device Type" "10120818-001C-TRLF"
			(at -20.7645 -10.5029 270)
			(unlocked yes)
			(layer "F.Fab")
			(hide yes)
			(effects
				(font
					(size 1.016 1.016)
					(thickness 0.1524)
				)
			)
		)
		(duplicate_pad_numbers_are_jumpers no)
		(fp_line
			(start 1.651 4.2926)
			(end 1.651 3.0099)
			(stroke
				(width 0.1524)
				(type default)
			)
			(layer "F.SilkS")
		)
		(fp_line
			(start 8.509 4.2926)
			(end 1.651 4.2926)
			(stroke
				(width 0.1524)
				(type default)
			)
			(layer "F.SilkS")
		)
		(fp_line
			(start -23.4188 3.0099)
			(end -23.4188 -3.2512)
			(stroke
				(width 0.1524)
				(type default)
			)
			(layer "F.SilkS")
		)
		(fp_line
			(start 1.651 3.0099)
			(end -23.4188 3.0099)
			(stroke
				(width 0.1524)
				(type default)
			)
			(layer "F.SilkS")
		)
		(fp_line
			(start 8.509 3.0099)
			(end 8.509 4.2926)
			(stroke
				(width 0.1524)
				(type default)
			)
			(layer "F.SilkS")
		)
		(fp_line
			(start 23.4188 3.0099)
			(end 8.509 3.0099)
			(stroke
				(width 0.1524)
				(type default)
			)
			(layer "F.SilkS")
		)
		(fp_line
			(start -23.4188 -3.2512)
			(end 23.4188 -3.2512)
			(stroke
				(width 0.1524)
				(type default)
			)
			(layer "F.SilkS")
		)
		(fp_line
			(start 23.4188 -3.2512)
			(end 23.4188 3.0099)
			(stroke
				(width 0.1524)
				(type default)
			)
			(layer "F.SilkS")
		)
		(fp_line
			(start 15.5067 -3.3401)
			(end 16.2687 -3.3401)
			(stroke
				(width 0.3302)
				(type default)
			)
			(layer "F.SilkS")
		)
		(fp_poly
			(pts
				(xy 15.868904 -3.230372) (xy 16.503904 -3.865372) (xy 15.233904 -3.865372)
			)
			(stroke
				(width 0)
				(type default)
			)
			(fill yes)
			(layer "F.SilkS")
		)
		(fp_poly
			(pts
				(xy -22.8727 -2.7559) (xy 22.8727 -2.7559) (xy 22.8727 2.7559) (xy 8.255 2.7559) (xy 8.255 3.5179)
				(xy 1.905 3.5179) (xy 1.905 2.7559) (xy -22.8727 2.7559)
			)
			(stroke
				(width 0)
				(type default)
			)
			(fill no)
			(layer "F.CrtYd")
		)
		(fp_poly
			(pts
				(xy 1.397 4.5466) (xy 1.397 3.2639) (xy -23.6728 3.2639) (xy -23.6728 -3.5052) (xy 23.6728 -3.5052)
				(xy 23.6728 -0.00635) (xy 22.8727 -0.00635) (xy 22.8727 -2.7559) (xy -22.8727 -2.7559) (xy -22.8727 2.7559)
				(xy 1.905 2.7559) (xy 1.905 3.5179) (xy 8.255 3.5179) (xy 8.255 2.7559) (xy 22.8727 2.7559) (xy 22.8727 0.00635)
				(xy 23.6728 0.00635) (xy 23.6728 3.2639) (xy 8.763 3.2639) (xy 8.763 4.5466)
			)
			(stroke
				(width 0)
				(type default)
			)
			(fill no)
			(layer "F.CrtYd")
		)
		(fp_poly
			(pts
				(xy 1.397 4.5466) (xy 1.397 3.2639) (xy -23.6728 3.2639) (xy -23.6728 -3.5052) (xy 23.6728 -3.5052)
				(xy 23.6728 3.2639) (xy 8.763 3.2639) (xy 8.763 4.5466)
			)
			(stroke
				(width 0)
				(type default)
			)
			(fill no)
			(layer "F.Fab")
		)
		(pad "" np_thru_hole circle
			(at -18.874994 0 270)
			(size 0.254 0.254)
			(drill 1.3462)
			(layers "*.Cu" "*.Mask")
			(clearance 0.9017)
			(thermal_gap 0.9017)
		)
		(pad "" np_thru_hole circle
			(at 18.874994 0 270)
			(size 0.254 0.254)
			(drill 0.9398)
			(layers "*.Cu" "*.Mask")
			(clearance 0.6985)
			(thermal_gap 0.6985)
		)
		(pad "G1" smd rect
			(at 21.874988 0 270)
			(size 2.5908 2.5908)
			(layers "F.Cu" "F.Mask" "F.Paste")
			(net "GND")
		)
		(pad "G2" smd rect
			(at -21.874988 0 270)
			(size 2.5908 2.5908)
			(layers "F.Cu" "F.Mask" "F.Paste")
			(net "GND")
		)
		(pad "P1" smd rect
			(at 1.905 -1.82499 270)
			(size 0.6096 2.3622)
			(layers "F.Cu" "F.Mask" "F.Paste")
			(net "Net_1679")
		)
		(pad "P2" smd rect
			(at 0.635 -1.82499 270)
			(size 0.6096 2.3622)
			(layers "F.Cu" "F.Mask" "F.Paste")
			(net "Net_1680")
		)
		(pad "P3" smd rect
			(at -0.635 -1.82499 270)
			(size 0.6096 2.3622)
			(layers "F.Cu" "F.Mask" "F.Paste")
			(net "Net_1681")
		)
		(pad "P4" smd rect
			(at -1.905 -1.82499 270)
			(size 0.6096 2.3622)
			(layers "F.Cu" "F.Mask" "F.Paste")
			(net "GND")
		)
		(pad "P5" smd rect
			(at -3.175 -1.82499 270)
			(size 0.6096 2.3622)
			(layers "F.Cu" "F.Mask" "F.Paste")
			(net "HDD_PRSNT_24")
		)
		(pad "P6" smd rect
			(at -4.445 -1.82499 270)
			(size 0.6096 2.3622)
			(layers "F.Cu" "F.Mask" "F.Paste")
			(net "GND")
		)
		(pad "P7" smd rect
			(at -5.715 -1.82499 270)
			(size 0.6096 2.3622)
			(layers "F.Cu" "F.Mask" "F.Paste")
			(net "5V_PRE_24")
		)
		(pad "P8" smd rect
			(at -6.985 -1.82499 270)
			(size 0.6096 2.3622)
			(layers "F.Cu" "F.Mask" "F.Paste")
			(net "P5V_HDD24")
		)
		(pad "P9" smd rect
			(at -8.255 -1.82499 270)
			(size 0.6096 2.3622)
			(layers "F.Cu" "F.Mask" "F.Paste")
			(net "P5V_HDD24")
		)
		(pad "P10" smd rect
			(at -9.525 -1.82499 270)
			(size 0.6096 2.3622)
			(layers "F.Cu" "F.Mask" "F.Paste")
			(net "GND")
		)
		(pad "P11" smd rect
			(at -10.795 -1.82499 270)
			(size 0.6096 2.3622)
			(layers "F.Cu" "F.Mask" "F.Paste")
			(net "ACT_HDD_24")
		)
		(pad "P12" smd rect
			(at -12.065 -1.82499 270)
			(size 0.6096 2.3622)
			(layers "F.Cu" "F.Mask" "F.Paste")
			(net "GND")
		)
		(pad "P13" smd rect
			(at -13.335 -1.82499 270)
			(size 0.6096 2.3622)
			(layers "F.Cu" "F.Mask" "F.Paste")
			(net "12V_PRE_24")
		)
		(pad "P14" smd rect
			(at -14.605 -1.82499 270)
			(size 0.6096 2.3622)
			(layers "F.Cu" "F.Mask" "F.Paste")
			(net "P12V_HDD24")
		)
		(pad "P15" smd rect
			(at -15.875 -1.82499 270)
			(size 0.6096 2.3622)
			(layers "F.Cu" "F.Mask" "F.Paste")
			(net "P12V_HDD24")
		)
		(pad "S1" smd rect
			(at 15.875 -1.82499 270)
			(size 0.6096 2.3622)
			(layers "F.Cu" "F.Mask" "F.Paste")
			(net "GND")
		)
		(pad "S2" smd rect
			(at 14.605 -1.82499 270)
			(size 0.6096 2.3622)
			(layers "F.Cu" "F.Mask" "F.Paste")
			(net "SAS_HDD_RX_P24")
		)
		(pad "S3" smd rect
			(at 13.335 -1.82499 270)
			(size 0.6096 2.3622)
			(layers "F.Cu" "F.Mask" "F.Paste")
			(net "SAS_HDD_RX_N24")
		)
		(pad "S4" smd rect
			(at 12.065 -1.82499 270)
			(size 0.6096 2.3622)
			(layers "F.Cu" "F.Mask" "F.Paste")
			(net "GND")
		)
		(pad "S5" smd rect
			(at 10.795 -1.82499 270)
			(size 0.6096 2.3622)
			(layers "F.Cu" "F.Mask" "F.Paste")
			(net "PHY_DRV_B_TO_SCC_B_24_DN")
		)
		(pad "S6" smd rect
			(at 9.525 -1.82499 270)
			(size 0.6096 2.3622)
			(layers "F.Cu" "F.Mask" "F.Paste")
			(net "PHY_DRV_B_TO_SCC_B_24_DP")
		)
		(pad "S7" smd rect
			(at 8.255 -1.82499 270)
			(size 0.6096 2.3622)
			(layers "F.Cu" "F.Mask" "F.Paste")
			(net "GND")
		)
		(pad "S8" smd rect
			(at 7.480046 2.845054 270)
			(size 0.508 2.3622)
			(layers "F.Cu" "F.Mask" "F.Paste")
			(net "GND")
		)
		(pad "S9" smd rect
			(at 6.679946 2.845054 270)
			(size 0.508 2.3622)
			(layers "F.Cu" "F.Mask" "F.Paste")
			(net "Net_448")
		)
		(pad "S10" smd rect
			(at 5.8801 2.845054 270)
			(size 0.508 2.3622)
			(layers "F.Cu" "F.Mask" "F.Paste")
			(net "Net_340")
		)
		(pad "S11" smd rect
			(at 5.08 2.845054 270)
			(size 0.508 2.3622)
			(layers "F.Cu" "F.Mask" "F.Paste")
			(net "GND")
		)
		(pad "S12" smd rect
			(at 4.2799 2.845054 270)
			(size 0.508 2.3622)
			(layers "F.Cu" "F.Mask" "F.Paste")
			(net "Net_376")
		)
		(pad "S13" smd rect
			(at 3.480054 2.845054 270)
			(size 0.508 2.3622)
			(layers "F.Cu" "F.Mask" "F.Paste")
			(net "Net_412")
		)
		(pad "S14" smd rect
			(at 2.679954 2.845054 270)
			(size 0.508 2.3622)
			(layers "F.Cu" "F.Mask" "F.Paste")
			(net "GND")
		)
		(zone
			(layer "F.Cu")
			(hatch none 0.5)
			(connect_pads
				(clearance 0)
			)
			(min_thickness 0.25)
			(keepout
				(tracks allowed)
				(vias not_allowed)
				(pads allowed)
				(copperpour not_allowed)
				(footprints allowed)
			)
			(placement
				(enabled no)
				(sheetname "")
			)
			(fill
				(thermal_gap 0.5)
				(thermal_bridge_width 0.5)
				(island_removal_mode 0)
			)
			(polygon
				(pts
					(xy 31.857696 -45.648626) (xy 24.783796 -45.648626) (xy 24.783796 -52.582826) (xy 25.888696 -52.582826)
					(xy 25.888696 -48.468026) (xy 30.511496 -48.468026) (xy 30.511496 -52.582826) (xy 31.857696 -52.582826)
				)
			)
		)
		(zone
			(layer "F.Cu")
			(hatch none 0.5)
			(connect_pads
				(clearance 0)
			)
			(min_thickness 0.25)
			(keepout
				(tracks not_allowed)
				(vias allowed)
				(pads allowed)
				(copperpour not_allowed)
				(footprints allowed)
			)
			(placement
				(enabled no)
				(sheetname "")
			)
			(fill
				(thermal_gap 0.5)
				(thermal_bridge_width 0.5)
				(island_removal_mode 0)
			)
			(polygon
				(pts
					(xy 31.857696 -45.648626) (xy 24.783796 -45.648626) (xy 24.783796 -52.582826) (xy 25.888696 -52.582826)
					(xy 25.888696 -48.468026) (xy 30.511496 -48.468026) (xy 30.511496 -52.582826) (xy 31.857696 -52.582826)
				)
			)
		)
		(zone
			(layer "F.Cu")
			(hatch none 0.5)
			(connect_pads
				(clearance 0)
			)
			(min_thickness 0.25)
			(keepout
				(tracks allowed)
				(vias not_allowed)
				(pads allowed)
				(copperpour not_allowed)
				(footprints allowed)
			)
			(placement
				(enabled no)
				(sheetname "")
			)
			(fill
				(thermal_gap 0.5)
				(thermal_bridge_width 0.5)
				(island_removal_mode 0)
			)
			(polygon
				(pts
					(xy 31.857696 -12.171426) (xy 24.783796 -12.171426) (xy 24.783796 -5.237226) (xy 25.888696 -5.237226)
					(xy 25.888696 -9.352026) (xy 30.511496 -9.352026) (xy 30.511496 -5.237226) (xy 31.857696 -5.237226)
				)
			)
		)
		(zone
			(layer "F.Cu")
			(hatch none 0.5)
			(connect_pads
				(clearance 0)
			)
			(min_thickness 0.25)
			(keepout
				(tracks not_allowed)
				(vias allowed)
				(pads allowed)
				(copperpour not_allowed)
				(footprints allowed)
			)
			(placement
				(enabled no)
				(sheetname "")
			)
			(fill
				(thermal_gap 0.5)
				(thermal_bridge_width 0.5)
				(island_removal_mode 0)
			)
			(polygon
				(pts
					(xy 31.857696 -12.171426) (xy 24.783796 -12.171426) (xy 24.783796 -5.237226) (xy 25.888696 -5.237226)
					(xy 25.888696 -9.352026) (xy 30.511496 -9.352026) (xy 30.511496 -5.237226) (xy 31.857696 -5.237226)
				)
			)
		)
		(zone
			(layers "F.Cu" "B.Cu" "In1.Cu" "In2.Cu" "In3.Cu" "In4.Cu" "In5.Cu" "In6.Cu")
			(hatch none 0.5)
			(connect_pads
				(clearance 0)
			)
			(min_thickness 0.25)
			(keepout
				(tracks not_allowed)
				(vias allowed)
				(pads allowed)
				(copperpour not_allowed)
				(footprints allowed)
			)
			(placement
				(enabled no)
				(sheetname "")
			)
			(fill
				(thermal_gap 0.5)
				(thermal_bridge_width 0.5)
				(island_removal_mode 0)
			)
			(polygon
				(pts
					(arc
						(start 28.974796 -10.035032)
						(mid 27.425396 -10.035032)
						(end 28.974796 -10.035032)
					)
				)
			)
		)
		(zone
			(layers "F.Cu" "B.Cu" "In1.Cu" "In2.Cu" "In3.Cu" "In4.Cu" "In5.Cu" "In6.Cu")
			(hatch none 0.5)
			(connect_pads
				(clearance 0)
			)
			(min_thickness 0.25)
			(keepout
				(tracks not_allowed)
				(vias allowed)
				(pads allowed)
				(copperpour not_allowed)
				(footprints allowed)
			)
			(placement
				(enabled no)
				(sheetname "")
			)
			(fill
				(thermal_gap 0.5)
				(thermal_bridge_width 0.5)
				(island_removal_mode 0)
			)
			(polygon
				(pts
					(arc
						(start 29.177996 -47.78502)
						(mid 27.222196 -47.78502)
						(end 29.177996 -47.78502)
					)
				)
			)
		)
	)
	(footprint ""
		(layer "F.Cu")
		(at 32.463486 -129.66065 90)
		(property "Reference" "C185"
			(at 0 0 90)
			(layer "F.SilkS")
			(hide yes)
			(effects
				(font
					(size 1.27 1.27)
				)
			)
		)
		(property "Value" "SCD01U16V1KX-GP"
			(at -2.8321 -1.7399 90)
			(unlocked yes)
			(layer "F.Fab")
			(hide yes)
			(effects
				(font
					(size 1.016 1.016)
					(thickness 0.1524)
				)
			)
		)
		(property "Device Type" "C0201H13"
			(at -2.8321 -3.2639 90)
			(unlocked yes)
			(layer "F.Fab")
			(hide yes)
			(effects
				(font
					(size 1.016 1.016)
					(thickness 0.1524)
				)
			)
		)
		(duplicate_pad_numbers_are_jumpers no)
		(fp_rect
			(start -0.2794 0.6477)
			(end 0.2794 -0.6477)
			(stroke
				(width 0)
				(type default)
			)
			(fill no)
			(layer "F.CrtYd")
		)
		(fp_rect
			(start -0.2794 0.6477)
			(end 0.2794 -0.6477)
			(stroke
				(width 0)
				(type default)
			)
			(fill no)
			(layer "F.Fab")
		)
		(pad "1" smd custom
			(at 0 -0.2794 90)
			(size 0.0762 0.0762)
			(layers "F.Cu" "F.Mask" "F.Paste")
			(net "SAS_HDD_RX_P12")
			(options
				(clearance outline)
				(anchor circle)
			)
			(primitives
				(gr_poly
					(pts
						(arc
							(start 0.1524 -0.127)
							(mid 0.137521 -0.162921)
							(end 0.1016 -0.1778)
						)
						(arc
							(start -0.1016 -0.1778)
							(mid -0.137521 -0.162921)
							(end -0.1524 -0.127)
						)
						(arc
							(start -0.1524 0.127)
							(mid -0.137521 0.162921)
							(end -0.1016 0.1778)
						)
						(arc
							(start 0.1016 0.1778)
							(mid 0.137521 0.162921)
							(end 0.1524 0.127)
						)
					)
					(width 0)
					(fill yes)
				)
			)
		)
		(pad "2" smd custom
			(at 0 0.2794 90)
			(size 0.0762 0.0762)
			(layers "F.Cu" "F.Mask" "F.Paste")
			(net "PHY_SCC_B_TO_DRV_B_12_DP")
			(options
				(clearance outline)
				(anchor circle)
			)
			(primitives
				(gr_poly
					(pts
						(arc
							(start 0.1524 -0.127)
							(mid 0.137521 -0.162921)
							(end 0.1016 -0.1778)
						)
						(arc
							(start -0.1016 -0.1778)
							(mid -0.137521 -0.162921)
							(end -0.1524 -0.127)
						)
						(arc
							(start -0.1524 0.127)
							(mid -0.137521 0.162921)
							(end -0.1016 0.1778)
						)
						(arc
							(start 0.1016 0.1778)
							(mid 0.137521 0.162921)
							(end 0.1524 0.127)
						)
					)
					(width 0)
					(fill yes)
				)
			)
		)
	)
	(footprint ""
		(layer "F.Cu")
		(at 143.002 -139.065 -90)
		(property "Reference" "C246"
			(at 0 0 270)
			(layer "F.SilkS")
			(hide yes)
			(effects
				(font
					(size 1.27 1.27)
				)
			)
		)
		(property "Value" "SCD033U25V2KX-GP"
			(at 1.1811 -2.7051 270)
			(unlocked yes)
			(layer "F.Fab")
			(hide yes)
			(effects
				(font
					(size 1.016 1.016)
					(thickness 0.1524)
				)
			)
		)
		(property "Device Type" "C402H22"
			(at 1.1811 -4.2291 270)
			(unlocked yes)
			(layer "F.Fab")
			(hide yes)
			(effects
				(font
					(size 1.016 1.016)
					(thickness 0.1524)
				)
			)
		)
		(duplicate_pad_numbers_are_jumpers no)
		(fp_rect
			(start -0.4318 0.9525)
			(end 0.4318 -0.9525)
			(stroke
				(width 0)
				(type default)
			)
			(fill no)
			(layer "F.CrtYd")
		)
		(fp_rect
			(start -0.4318 0.9525)
			(end 0.4318 -0.9525)
			(stroke
				(width 0)
				(type default)
			)
			(fill no)
			(layer "F.Fab")
		)
		(pad "1" smd custom
			(at 0 -0.4445 270)
			(size 0.1524 0.1524)
			(layers "F.Cu" "F.Mask" "F.Paste")
			(net "SW_HDD_P16")
			(options
				(clearance outline)
				(anchor circle)
			)
			(primitives
				(gr_poly
					(pts
						(arc
							(start 0.3048 -0.2032)
							(mid 0.275042 -0.275042)
							(end 0.2032 -0.3048)
						)
						(arc
							(start -0.2032 -0.3048)
							(mid -0.275042 -0.275042)
							(end -0.3048 -0.2032)
						)
						(arc
							(start -0.3048 0.2032)
							(mid -0.275042 0.275042)
							(end -0.2032 0.3048)
						)
						(arc
							(start 0.2032 0.3048)
							(mid 0.275042 0.275042)
							(end 0.3048 0.2032)
						)
					)
					(width 0)
					(fill yes)
				)
			)
		)
		(pad "2" smd custom
			(at 0 0.4445 270)
			(size 0.1524 0.1524)
			(layers "F.Cu" "F.Mask" "F.Paste")
			(net "GND")
			(options
				(clearance outline)
				(anchor circle)
			)
			(primitives
				(gr_poly
					(pts
						(arc
							(start 0.3048 -0.2032)
							(mid 0.275042 -0.275042)
							(end 0.2032 -0.3048)
						)
						(arc
							(start -0.2032 -0.3048)
							(mid -0.275042 -0.275042)
							(end -0.3048 -0.2032)
						)
						(arc
							(start -0.3048 0.2032)
							(mid -0.275042 0.275042)
							(end -0.2032 0.3048)
						)
						(arc
							(start 0.2032 0.3048)
							(mid 0.275042 0.275042)
							(end 0.3048 0.2032)
						)
					)
					(width 0)
					(fill yes)
				)
			)
		)
	)
)
